FILE_TYPE=LIBRARY_PARTS;
primitive '74LVC1G17GW';
  pin
    'VCC':
      PIN_NUMBER='(5)';
      PINUSE='POWER';
      NO_LOAD_CHECK='Both';
      NO_IO_CHECK='Both';
      NO_ASSERT_CHECK='TRUE';
      NO_DIR_CHECK='TRUE';
      ALLOW_CONNECT='TRUE';
    'A':
      PIN_NUMBER='(2)';
      INPUT_LOAD='(-0.01,0.01)';
    'GND':
      PIN_NUMBER='(3)';
      PINUSE='POWER';
      NO_LOAD_CHECK='Both';
      NO_IO_CHECK='Both';
      NO_ASSERT_CHECK='TRUE';
      NO_DIR_CHECK='TRUE';
      ALLOW_CONNECT='TRUE';
    'Y':
      PIN_NUMBER='(4)';
      OUTPUT_TYPE='(OC,AND)';
      OUTPUT_LOAD='(1.0,*)';
    'NC':
      PIN_NUMBER='(1)';
      OUTPUT_TYPE='(TS,TS)';
      INPUT_LOAD='(-0.01,0.01)';
      OUTPUT_LOAD='(1.0,-1.0)';
  end_pin;
  body
    PART_NAME='74LVC1G17GW';
    BODY_NAME='74LVC1G17GW';
    PHYS_DES_PREFIX='U';
    CLASS='IC';
  end_body;
end_primitive;

END.
